(kicad_pcb
	(version 20260206)
	(generator "pcbnew")
	(generator_version "10.0")
	(general
		(thickness 1.6)
		(legacy_teardrops no)
	)
	(paper "A4")
	(title_block
		(title "01162023_DA0F0TEBIF0_F0T_Expander_BD_F_brd_V02_OCP.brd")
		(comment 1 "Grand Teton / footprints 2023-2028 of 9728")
	)
	(layers
		(0 "F.Cu" signal "TOP")
		(4 "In1.Cu" signal "GND")
		(6 "In2.Cu" signal "VCC")
		(8 "In3.Cu" signal "VCC1")
		(10 "In4.Cu" signal "GND1")
		(12 "In5.Cu" signal "IN1")
		(14 "In6.Cu" signal "GND2")
		(16 "In7.Cu" signal "IN2")
		(18 "In8.Cu" signal "GND3")
		(20 "In9.Cu" signal "IN3")
		(22 "In10.Cu" signal "GND4")
		(24 "In11.Cu" signal "IN4")
		(26 "In12.Cu" signal "GND5")
		(28 "In13.Cu" signal "IN5")
		(30 "In14.Cu" signal "GND6")
		(32 "In15.Cu" signal "IN6")
		(34 "In16.Cu" signal "GND7")
		(2 "B.Cu" signal "BOTTOM")
		(9 "F.Adhes" user "F.Adhesive")
		(11 "B.Adhes" user "B.Adhesive")
		(13 "F.Paste" user "Package Geometry/Pastemask Top")
		(15 "B.Paste" user "Package Geometry/Pastemask Bottom")
		(5 "F.SilkS" user "Ref Des/Silkscreen Top")
		(7 "B.SilkS" user "Ref Des/Silkscreen Bottom")
		(1 "F.Mask" user "Board Geometry/Soldermask Top")
		(3 "B.Mask" user "Board Geometry/Soldermask Bottom")
		(17 "Dwgs.User" user "User.Drawings")
		(19 "Cmts.User" user "User.Comments")
		(21 "Eco1.User" user "User.Eco1")
		(23 "Eco2.User" user "User.Eco2")
		(25 "Edge.Cuts" user "Board Geometry/Outline")
		(27 "Margin" user)
		(31 "F.CrtYd" user "Package Geometry/Place Bound Top")
		(29 "B.CrtYd" user "Package Geometry/Place Bound Bottom")
		(35 "F.Fab" user "Ref Des/Assembly Top")
		(33 "B.Fab" user "Ref Des/Assembly Bottom")
	)
	(footprint ""
		(layer "F.Cu")
		(at 222.663512 -231.416606 90)
		(property "Reference" "R4545"
			(at 0 0 90)
			(layer "F.SilkS")
			(hide yes)
			(effects
				(font
					(size 1.27 1.27)
				)
			)
		)
		(property "Value" ""
			(at 0 0 90)
			(layer "F.Fab")
			(effects
				(font
					(size 1.27 1.27)
				)
			)
		)
		(duplicate_pad_numbers_are_jumpers no)
		(fp_line
			(start 0.7874 -0.4064)
			(end 0.7874 0.4064)
			(stroke
				(width 0.1524)
				(type default)
			)
			(layer "F.SilkS")
		)
		(fp_line
			(start -0.7874 -0.4064)
			(end 0.7874 -0.4064)
			(stroke
				(width 0.1524)
				(type default)
			)
			(layer "F.SilkS")
		)
		(fp_line
			(start 0.7874 0.4064)
			(end -0.7874 0.4064)
			(stroke
				(width 0.1524)
				(type default)
			)
			(layer "F.SilkS")
		)
		(fp_line
			(start -0.7874 0.4064)
			(end -0.7874 -0.4064)
			(stroke
				(width 0.1524)
				(type default)
			)
			(layer "F.SilkS")
		)
		(fp_line
			(start -0.12065 -0.305054)
			(end -0.12065 -0.2794)
			(stroke
				(width 0.1)
				(type default)
			)
			(layer "F.Fab")
		)
		(fp_line
			(start -0.67945 -0.305054)
			(end -0.12065 -0.305054)
			(stroke
				(width 0.1)
				(type default)
			)
			(layer "F.Fab")
		)
		(fp_line
			(start 0.67945 -0.3048)
			(end 0.67945 0.3048)
			(stroke
				(width 0.1)
				(type default)
			)
			(layer "F.Fab")
		)
		(fp_line
			(start 0.12065 -0.3048)
			(end 0.67945 -0.3048)
			(stroke
				(width 0.1)
				(type default)
			)
			(layer "F.Fab")
		)
		(fp_line
			(start 0.12065 -0.2794)
			(end 0.12065 -0.3048)
			(stroke
				(width 0.1)
				(type default)
			)
			(layer "F.Fab")
		)
		(fp_line
			(start -0.12065 -0.2794)
			(end 0.12065 -0.2794)
			(stroke
				(width 0.1)
				(type default)
			)
			(layer "F.Fab")
		)
		(fp_line
			(start 0.120396 0.2794)
			(end -0.12065 0.2794)
			(stroke
				(width 0.1)
				(type default)
			)
			(layer "F.Fab")
		)
		(fp_line
			(start -0.12065 0.2794)
			(end -0.12065 0.3048)
			(stroke
				(width 0.1)
				(type default)
			)
			(layer "F.Fab")
		)
		(fp_line
			(start 0.67945 0.3048)
			(end 0.120396 0.3048)
			(stroke
				(width 0.1)
				(type default)
			)
			(layer "F.Fab")
		)
		(fp_line
			(start 0.120396 0.3048)
			(end 0.120396 0.2794)
			(stroke
				(width 0.1)
				(type default)
			)
			(layer "F.Fab")
		)
		(fp_line
			(start -0.12065 0.3048)
			(end -0.67945 0.3048)
			(stroke
				(width 0.1)
				(type default)
			)
			(layer "F.Fab")
		)
		(fp_line
			(start -0.67945 0.3048)
			(end -0.67945 -0.305054)
			(stroke
				(width 0.1)
				(type default)
			)
			(layer "F.Fab")
		)
		(pad "1" smd circle
			(at -0.40005 0 90)
			(size 0 0)
			(layers "F.Cu" "F.Mask" "F.Paste")
			(net "REV_ID1")
		)
		(pad "2" smd circle
			(at 0.40005 0 90)
			(size 0 0)
			(layers "F.Cu" "F.Mask" "F.Paste")
			(net "P3V3_AUX")
		)
	)
	(footprint ""
		(layer "F.Cu")
		(at 98.048318 -396.1638)
		(property "Reference" "R5459"
			(at 0 0 0)
			(layer "F.SilkS")
			(hide yes)
			(effects
				(font
					(size 1.27 1.27)
				)
			)
		)
		(property "Value" ""
			(at 0 0 0)
			(layer "F.Fab")
			(effects
				(font
					(size 1.27 1.27)
				)
			)
		)
		(duplicate_pad_numbers_are_jumpers no)
		(fp_line
			(start -0.7874 -0.4064)
			(end 0.7874 -0.4064)
			(stroke
				(width 0.1524)
				(type default)
			)
			(layer "F.SilkS")
		)
		(fp_line
			(start -0.7874 0.4064)
			(end -0.7874 -0.4064)
			(stroke
				(width 0.1524)
				(type default)
			)
			(layer "F.SilkS")
		)
		(fp_line
			(start 0.7874 -0.4064)
			(end 0.7874 0.4064)
			(stroke
				(width 0.1524)
				(type default)
			)
			(layer "F.SilkS")
		)
		(fp_line
			(start 0.7874 0.4064)
			(end -0.7874 0.4064)
			(stroke
				(width 0.1524)
				(type default)
			)
			(layer "F.SilkS")
		)
		(fp_line
			(start -0.67945 -0.305054)
			(end -0.12065 -0.305054)
			(stroke
				(width 0.1)
				(type default)
			)
			(layer "F.Fab")
		)
		(fp_line
			(start -0.67945 0.3048)
			(end -0.67945 -0.305054)
			(stroke
				(width 0.1)
				(type default)
			)
			(layer "F.Fab")
		)
		(fp_line
			(start -0.12065 -0.305054)
			(end -0.12065 -0.2794)
			(stroke
				(width 0.1)
				(type default)
			)
			(layer "F.Fab")
		)
		(fp_line
			(start -0.12065 -0.2794)
			(end 0.12065 -0.2794)
			(stroke
				(width 0.1)
				(type default)
			)
			(layer "F.Fab")
		)
		(fp_line
			(start -0.12065 0.2794)
			(end -0.12065 0.3048)
			(stroke
				(width 0.1)
				(type default)
			)
			(layer "F.Fab")
		)
		(fp_line
			(start -0.12065 0.3048)
			(end -0.67945 0.3048)
			(stroke
				(width 0.1)
				(type default)
			)
			(layer "F.Fab")
		)
		(fp_line
			(start 0.120396 0.2794)
			(end -0.12065 0.2794)
			(stroke
				(width 0.1)
				(type default)
			)
			(layer "F.Fab")
		)
		(fp_line
			(start 0.120396 0.3048)
			(end 0.120396 0.2794)
			(stroke
				(width 0.1)
				(type default)
			)
			(layer "F.Fab")
		)
		(fp_line
			(start 0.12065 -0.3048)
			(end 0.67945 -0.3048)
			(stroke
				(width 0.1)
				(type default)
			)
			(layer "F.Fab")
		)
		(fp_line
			(start 0.12065 -0.2794)
			(end 0.12065 -0.3048)
			(stroke
				(width 0.1)
				(type default)
			)
			(layer "F.Fab")
		)
		(fp_line
			(start 0.67945 -0.3048)
			(end 0.67945 0.3048)
			(stroke
				(width 0.1)
				(type default)
			)
			(layer "F.Fab")
		)
		(fp_line
			(start 0.67945 0.3048)
			(end 0.120396 0.3048)
			(stroke
				(width 0.1)
				(type default)
			)
			(layer "F.Fab")
		)
		(pad "1" smd circle
			(at -0.40005 0)
			(size 0 0)
			(layers "F.Cu" "F.Mask" "F.Paste")
			(net "P3V3_AUX")
		)
		(pad "2" smd circle
			(at 0.40005 0)
			(size 0 0)
			(layers "F.Cu" "F.Mask" "F.Paste")
			(net "BIC_USB_HUB_PSELF")
		)
	)
	(footprint ""
		(layer "F.Cu")
		(at 146.18208 -283.389832 180)
		(property "Reference" "C3236"
			(at 0 0 180)
			(layer "F.SilkS")
			(hide yes)
			(effects
				(font
					(size 1.27 1.27)
				)
			)
		)
		(property "Value" ""
			(at 0 0 180)
			(layer "F.Fab")
			(effects
				(font
					(size 1.27 1.27)
				)
			)
		)
		(duplicate_pad_numbers_are_jumpers no)
		(fp_line
			(start 1.2954 0.5842)
			(end -1.2954 0.5842)
			(stroke
				(width 0.1524)
				(type default)
			)
			(layer "F.SilkS")
		)
		(fp_line
			(start 1.2954 -0.5842)
			(end 1.2954 0.5842)
			(stroke
				(width 0.1524)
				(type default)
			)
			(layer "F.SilkS")
		)
		(fp_line
			(start -1.2954 0.5842)
			(end -1.2954 -0.5842)
			(stroke
				(width 0.1524)
				(type default)
			)
			(layer "F.SilkS")
		)
		(fp_line
			(start -1.2954 -0.5842)
			(end 1.2954 -0.5842)
			(stroke
				(width 0.1524)
				(type default)
			)
			(layer "F.SilkS")
		)
		(fp_line
			(start 1.1938 0.4064)
			(end 0.8636 0.4064)
			(stroke
				(width 0.1)
				(type default)
			)
			(layer "F.Fab")
		)
		(fp_line
			(start 1.1938 -0.4064)
			(end 1.1938 0.4064)
			(stroke
				(width 0.1)
				(type default)
			)
			(layer "F.Fab")
		)
		(fp_line
			(start 0.8636 0.4572)
			(end -0.8636 0.4572)
			(stroke
				(width 0.1)
				(type default)
			)
			(layer "F.Fab")
		)
		(fp_line
			(start 0.8636 0.4064)
			(end 0.8636 0.4572)
			(stroke
				(width 0.1)
				(type default)
			)
			(layer "F.Fab")
		)
		(fp_line
			(start 0.8636 -0.4064)
			(end 1.1938 -0.4064)
			(stroke
				(width 0.1)
				(type default)
			)
			(layer "F.Fab")
		)
		(fp_line
			(start 0.8636 -0.4572)
			(end 0.8636 -0.4064)
			(stroke
				(width 0.1)
				(type default)
			)
			(layer "F.Fab")
		)
		(fp_line
			(start -0.8636 0.4572)
			(end -0.8636 0.4064)
			(stroke
				(width 0.1)
				(type default)
			)
			(layer "F.Fab")
		)
		(fp_line
			(start -0.8636 0.4064)
			(end -1.1938 0.4064)
			(stroke
				(width 0.1)
				(type default)
			)
			(layer "F.Fab")
		)
		(fp_line
			(start -0.8636 -0.4064)
			(end -0.8636 -0.4572)
			(stroke
				(width 0.1)
				(type default)
			)
			(layer "F.Fab")
		)
		(fp_line
			(start -0.8636 -0.4572)
			(end 0.8636 -0.4572)
			(stroke
				(width 0.1)
				(type default)
			)
			(layer "F.Fab")
		)
		(fp_line
			(start -1.1938 0.4064)
			(end -1.1938 -0.4064)
			(stroke
				(width 0.1)
				(type default)
			)
			(layer "F.Fab")
		)
		(fp_line
			(start -1.1938 -0.4064)
			(end -0.8636 -0.4064)
			(stroke
				(width 0.1)
				(type default)
			)
			(layer "F.Fab")
		)
		(pad "1" smd rect
			(at -0.7366 0 90)
			(size 0.7112 0.8128)
			(layers "F.Cu" "F.Mask" "F.Paste")
			(net "PCEPLL7_VDDA18_PEX1_R")
		)
		(pad "2" smd rect
			(at 0.7366 0 90)
			(size 0.7112 0.8128)
			(layers "F.Cu" "F.Mask" "F.Paste")
			(net "GND")
		)
	)
	(footprint ""
		(layer "F.Cu")
		(at 143.030194 -287.604708 -90)
		(property "Reference" "C3211"
			(at 0 0 270)
			(layer "F.SilkS")
			(hide yes)
			(effects
				(font
					(size 1.27 1.27)
				)
			)
		)
		(property "Value" ""
			(at 0 0 270)
			(layer "F.Fab")
			(effects
				(font
					(size 1.27 1.27)
				)
			)
		)
		(duplicate_pad_numbers_are_jumpers no)
		(fp_line
			(start -1.2954 0.5842)
			(end -1.2954 -0.5842)
			(stroke
				(width 0.1524)
				(type default)
			)
			(layer "F.SilkS")
		)
		(fp_line
			(start 1.2954 0.5842)
			(end -1.2954 0.5842)
			(stroke
				(width 0.1524)
				(type default)
			)
			(layer "F.SilkS")
		)
		(fp_line
			(start -1.2954 -0.5842)
			(end 1.2954 -0.5842)
			(stroke
				(width 0.1524)
				(type default)
			)
			(layer "F.SilkS")
		)
		(fp_line
			(start 1.2954 -0.5842)
			(end 1.2954 0.5842)
			(stroke
				(width 0.1524)
				(type default)
			)
			(layer "F.SilkS")
		)
		(fp_line
			(start -0.8636 0.4572)
			(end -0.8636 0.4064)
			(stroke
				(width 0.1)
				(type default)
			)
			(layer "F.Fab")
		)
		(fp_line
			(start 0.8636 0.4572)
			(end -0.8636 0.4572)
			(stroke
				(width 0.1)
				(type default)
			)
			(layer "F.Fab")
		)
		(fp_line
			(start -1.1938 0.4064)
			(end -1.1938 -0.4064)
			(stroke
				(width 0.1)
				(type default)
			)
			(layer "F.Fab")
		)
		(fp_line
			(start -0.8636 0.4064)
			(end -1.1938 0.4064)
			(stroke
				(width 0.1)
				(type default)
			)
			(layer "F.Fab")
		)
		(fp_line
			(start 0.8636 0.4064)
			(end 0.8636 0.4572)
			(stroke
				(width 0.1)
				(type default)
			)
			(layer "F.Fab")
		)
		(fp_line
			(start 1.1938 0.4064)
			(end 0.8636 0.4064)
			(stroke
				(width 0.1)
				(type default)
			)
			(layer "F.Fab")
		)
		(fp_line
			(start -1.1938 -0.4064)
			(end -0.8636 -0.4064)
			(stroke
				(width 0.1)
				(type default)
			)
			(layer "F.Fab")
		)
		(fp_line
			(start -0.8636 -0.4064)
			(end -0.8636 -0.4572)
			(stroke
				(width 0.1)
				(type default)
			)
			(layer "F.Fab")
		)
		(fp_line
			(start 0.8636 -0.4064)
			(end 1.1938 -0.4064)
			(stroke
				(width 0.1)
				(type default)
			)
			(layer "F.Fab")
		)
		(fp_line
			(start 1.1938 -0.4064)
			(end 1.1938 0.4064)
			(stroke
				(width 0.1)
				(type default)
			)
			(layer "F.Fab")
		)
		(fp_line
			(start -0.8636 -0.4572)
			(end 0.8636 -0.4572)
			(stroke
				(width 0.1)
				(type default)
			)
			(layer "F.Fab")
		)
		(fp_line
			(start 0.8636 -0.4572)
			(end 0.8636 -0.4064)
			(stroke
				(width 0.1)
				(type default)
			)
			(layer "F.Fab")
		)
		(pad "1" smd rect
			(at -0.7366 0 180)
			(size 0.7112 0.8128)
			(layers "F.Cu" "F.Mask" "F.Paste")
			(net "P1V8_PLL0_PEX1")
		)
		(pad "2" smd rect
			(at 0.7366 0 180)
			(size 0.7112 0.8128)
			(layers "F.Cu" "F.Mask" "F.Paste")
			(net "GND")
		)
	)
	(footprint ""
		(layer "F.Cu")
		(at 259.299964 -98.700082)
		(property "Reference" "H81"
			(at -6.874764 -7.013448 0)
			(unlocked yes)
			(layer "F.SilkS")
			(effects
				(font
					(size 0.7874 0.5842)
					(thickness 0.1524)
				)
				(justify left)
			)
		)
		(property "Value" ""
			(at 0 0 0)
			(layer "F.Fab")
			(effects
				(font
					(size 1.27 1.27)
				)
			)
		)
		(duplicate_pad_numbers_are_jumpers no)
		(fp_circle
			(center 0 0)
			(end 7.999984 0)
			(stroke
				(width 0.1524)
				(type default)
			)
			(fill no)
			(layer "F.SilkS")
		)
		(fp_circle
			(center 0 0)
			(end 7.999984 0)
			(stroke
				(width 0.1524)
				(type default)
			)
			(fill no)
			(layer "B.SilkS")
		)
		(fp_circle
			(center 0 0)
			(end 7.999984 0)
			(stroke
				(width 0.1)
				(type default)
			)
			(fill no)
			(layer "B.Fab")
		)
		(fp_circle
			(center 0 0)
			(end 7.999984 0)
			(stroke
				(width 0.1)
				(type default)
			)
			(fill no)
			(layer "F.Fab")
		)
		(pad "" np_thru_hole circle
			(at 0 0)
			(size 3.4036 3.4036)
			(drill 3.4036)
			(layers "*.Cu" "*.Mask")
			(clearance 0.381)
			(thermal_gap 0.381)
		)
		(pad "2" thru_hole circle
			(at 3.606292 0)
			(size 0.762 0.762)
			(drill 0.5588)
			(layers "*.Cu" "*.Mask")
			(remove_unused_layers no)
			(net "GND")
			(clearance 0.1524)
			(thermal_gap 0.1524)
		)
		(pad "3" thru_hole circle
			(at 2.549906 -2.549906)
			(size 0.762 0.762)
			(drill 0.5588)
			(layers "*.Cu" "*.Mask")
			(remove_unused_layers no)
			(net "GND")
			(clearance 0.1524)
			(thermal_gap 0.1524)
		)
		(pad "4" thru_hole circle
			(at 0 -3.606292)
			(size 0.762 0.762)
			(drill 0.5588)
			(layers "*.Cu" "*.Mask")
			(remove_unused_layers no)
			(net "GND")
			(clearance 0.1524)
			(thermal_gap 0.1524)
		)
		(pad "5" thru_hole circle
			(at -2.549906 -2.549906)
			(size 0.762 0.762)
			(drill 0.5588)
			(layers "*.Cu" "*.Mask")
			(remove_unused_layers no)
			(net "GND")
			(clearance 0.1524)
			(thermal_gap 0.1524)
		)
		(pad "6" thru_hole circle
			(at -3.606292 0)
			(size 0.762 0.762)
			(drill 0.5588)
			(layers "*.Cu" "*.Mask")
			(remove_unused_layers no)
			(net "GND")
			(clearance 0.1524)
			(thermal_gap 0.1524)
		)
		(pad "7" thru_hole circle
			(at -2.549906 2.549906)
			(size 0.762 0.762)
			(drill 0.5588)
			(layers "*.Cu" "*.Mask")
			(remove_unused_layers no)
			(net "GND")
			(clearance 0.1524)
			(thermal_gap 0.1524)
		)
		(pad "8" thru_hole circle
			(at 0 3.606292)
			(size 0.762 0.762)
			(drill 0.5588)
			(layers "*.Cu" "*.Mask")
			(remove_unused_layers no)
			(net "GND")
			(clearance 0.1524)
			(thermal_gap 0.1524)
		)
		(pad "9" thru_hole circle
			(at 2.549906 2.549906)
			(size 0.762 0.762)
			(drill 0.5588)
			(layers "*.Cu" "*.Mask")
			(remove_unused_layers no)
			(net "GND")
			(clearance 0.1524)
			(thermal_gap 0.1524)
		)
		(zone
			(layer "F.Cu")
			(hatch none 0.5)
			(connect_pads
				(clearance 0)
			)
			(min_thickness 0.25)
			(keepout
				(tracks not_allowed)
				(vias allowed)
				(pads allowed)
				(copperpour not_allowed)
				(footprints allowed)
			)
			(placement
				(enabled no)
				(sheetname "")
			)
			(fill
				(thermal_gap 0.5)
				(thermal_bridge_width 0.5)
				(island_removal_mode 0)
			)
			(polygon
				(pts
					(arc
						(start 259.299964 -90.700098)
						(mid 251.29998 -98.700082)
						(end 259.299964 -106.700066)
					)
					(arc
						(start 259.299964 -103.954072)
						(mid 254.045974 -98.700082)
						(end 259.299964 -93.446092)
					)
				)
			)
		)
		(zone
			(layer "F.Cu")
			(hatch none 0.5)
			(connect_pads
				(clearance 0)
			)
			(min_thickness 0.25)
			(keepout
				(tracks not_allowed)
				(vias allowed)
				(pads allowed)
				(copperpour not_allowed)
				(footprints allowed)
			)
			(placement
				(enabled no)
				(sheetname "")
			)
			(fill
				(thermal_gap 0.5)
				(thermal_bridge_width 0.5)
				(island_removal_mode 0)
			)
			(polygon
				(pts
					(arc
						(start 259.299964 -90.700098)
						(mid 267.299948 -98.700082)
						(end 259.299964 -106.700066)
					)
					(arc
						(start 259.299964 -103.954072)
						(mid 264.553954 -98.700082)
						(end 259.299964 -93.446092)
					)
				)
			)
		)
		(zone
			(layers "F.Cu" "B.Cu" "In1.Cu" "In2.Cu" "In3.Cu" "In4.Cu" "In5.Cu" "In6.Cu"
				"In7.Cu" "In8.Cu" "In9.Cu" "In10.Cu" "In11.Cu" "In12.Cu" "In13.Cu" "In14.Cu"
				"In15.Cu" "In16.Cu"
			)
			(hatch none 0.5)
			(connect_pads
				(clearance 0)
			)
			(min_thickness 0.25)
			(keepout
				(tracks not_allowed)
				(vias allowed)
				(pads allowed)
				(copperpour not_allowed)
				(footprints allowed)
			)
			(placement
				(enabled no)
				(sheetname "")
			)
			(fill
				(thermal_gap 0.5)
				(thermal_bridge_width 0.5)
				(island_removal_mode 0)
			)
			(polygon
				(pts
					(arc
						(start 261.509764 -98.700082)
						(mid 257.090164 -98.700082)
						(end 261.509764 -98.700082)
					)
				)
			)
		)
		(zone
			(layer "B.Cu")
			(hatch none 0.5)
			(connect_pads
				(clearance 0)
			)
			(min_thickness 0.25)
			(keepout
				(tracks not_allowed)
				(vias allowed)
				(pads allowed)
				(copperpour not_allowed)
				(footprints allowed)
			)
			(placement
				(enabled no)
				(sheetname "")
			)
			(fill
				(thermal_gap 0.5)
				(thermal_bridge_width 0.5)
				(island_removal_mode 0)
			)
			(polygon
				(pts
					(arc
						(start 259.299964 -93.192092)
						(mid 253.791974 -98.700082)
						(end 259.299964 -104.208072)
					)
					(arc
						(start 259.299964 -103.725472)
						(mid 254.274574 -98.700082)
						(end 259.299964 -93.674692)
					)
				)
			)
		)
		(zone
			(layer "B.Cu")
			(hatch none 0.5)
			(connect_pads
				(clearance 0)
			)
			(min_thickness 0.25)
			(keepout
				(tracks not_allowed)
				(vias allowed)
				(pads allowed)
				(copperpour not_allowed)
				(footprints allowed)
			)
			(placement
				(enabled no)
				(sheetname "")
			)
			(fill
				(thermal_gap 0.5)
				(thermal_bridge_width 0.5)
				(island_removal_mode 0)
			)
			(polygon
				(pts
					(arc
						(start 259.299964 -93.192092)
						(mid 264.807954 -98.700082)
						(end 259.299964 -104.208072)
					)
					(arc
						(start 259.299964 -103.725472)
						(mid 264.325354 -98.700082)
						(end 259.299964 -93.674692)
					)
				)
			)
		)
	)
	(footprint ""
		(layer "F.Cu")
		(at 362.077762 -378.764292 180)
		(property "Reference" "C4457"
			(at 0 0 180)
			(layer "F.SilkS")
			(hide yes)
			(effects
				(font
					(size 1.27 1.27)
				)
			)
		)
		(property "Value" ""
			(at 0 0 180)
			(layer "F.Fab")
			(effects
				(font
					(size 1.27 1.27)
				)
			)
		)
		(duplicate_pad_numbers_are_jumpers no)
		(fp_line
			(start 0.299974 0.150114)
			(end -0.299974 0.150114)
			(stroke
				(width 0.1)
				(type default)
			)
			(layer "F.Fab")
		)
		(fp_line
			(start 0.299974 -0.150114)
			(end 0.299974 0.150114)
			(stroke
				(width 0.1)
				(type default)
			)
			(layer "F.Fab")
		)
		(fp_line
			(start -0.299974 0.150114)
			(end -0.299974 -0.150114)
			(stroke
				(width 0.1)
				(type default)
			)
			(layer "F.Fab")
		)
		(fp_line
			(start -0.299974 -0.150114)
			(end 0.299974 -0.150114)
			(stroke
				(width 0.1)
				(type default)
			)
			(layer "F.Fab")
		)
		(pad "1" smd rect
			(at -0.2667 0 180)
			(size 0.3048 0.381)
			(layers "F.Cu" "F.Mask" "F.Paste")
			(net "MB_3V3IO_RSVD4_ISO")
		)
		(pad "2" smd rect
			(at 0.2667 0 180)
			(size 0.3048 0.381)
			(layers "F.Cu" "F.Mask" "F.Paste")
			(net "GND")
		)
	)
)
